(kicad_pcb
	(version 20260206)
	(generator "pcbnew")
	(generator_version "10.0")
	(general
		(thickness 1.6)
		(legacy_teardrops no)
	)
	(paper "A4")
	(title_block
		(title "03242023_DA0F0TMBIJ0_F0T_Motherboard_J_brd_V01_OCP.brd")
		(comment 1 "Grand Teton / footprints 971-977 of 6105")
	)
	(layers
		(0 "F.Cu" signal "TOP")
		(4 "In1.Cu" signal "GND")
		(6 "In2.Cu" signal "IN1")
		(8 "In3.Cu" signal "GND1")
		(10 "In4.Cu" signal "IN2")
		(12 "In5.Cu" signal "GND2")
		(14 "In6.Cu" signal "IN3")
		(16 "In7.Cu" signal "GND3")
		(18 "In8.Cu" signal "VCC")
		(20 "In9.Cu" signal "VCC1")
		(22 "In10.Cu" signal "GND4")
		(24 "In11.Cu" signal "IN4")
		(26 "In12.Cu" signal "GND5")
		(28 "In13.Cu" signal "IN5")
		(30 "In14.Cu" signal "GND6")
		(32 "In15.Cu" signal "IN6")
		(34 "In16.Cu" signal "GND7")
		(2 "B.Cu" signal "BOTTOM")
		(9 "F.Adhes" user "F.Adhesive")
		(11 "B.Adhes" user "B.Adhesive")
		(13 "F.Paste" user "Package Geometry/Pastemask Top")
		(15 "B.Paste" user "Package Geometry/Pastemask Bottom")
		(5 "F.SilkS" user "Ref Des/Silkscreen Top")
		(7 "B.SilkS" user "Ref Des/Silkscreen Bottom")
		(1 "F.Mask" user "Board Geometry/Soldermask Top")
		(3 "B.Mask" user "Board Geometry/Soldermask Bottom")
		(17 "Dwgs.User" user "User.Drawings")
		(19 "Cmts.User" user "User.Comments")
		(21 "Eco1.User" user "User.Eco1")
		(23 "Eco2.User" user "User.Eco2")
		(25 "Edge.Cuts" user "Board Geometry/Outline")
		(27 "Margin" user)
		(31 "F.CrtYd" user "Package Geometry/Place Bound Top")
		(29 "B.CrtYd" user "Package Geometry/Place Bound Bottom")
		(35 "F.Fab" user "Ref Des/Assembly Top")
		(33 "B.Fab" user "Ref Des/Assembly Bottom")
	)
	(footprint ""
		(layer "F.Cu")
		(at 44.36999 -164.39134)
		(property "Reference" "PC461"
			(at 0 0 0)
			(layer "F.SilkS")
			(hide yes)
			(effects
				(font
					(size 1.27 1.27)
				)
			)
		)
		(property "Value" ""
			(at 0 0 0)
			(layer "F.Fab")
			(effects
				(font
					(size 1.27 1.27)
				)
			)
		)
		(duplicate_pad_numbers_are_jumpers no)
		(fp_line
			(start -3.400044 1.249934)
			(end 3.400044 1.249934)
			(stroke
				(width 0.1524)
				(type default)
			)
			(layer "F.SilkS")
		)
		(fp_circle
			(center 0 1.249934)
			(end 3.400044 1.249934)
			(stroke
				(width 0.1524)
				(type default)
			)
			(fill no)
			(layer "F.SilkS")
		)
		(fp_poly
			(pts
				(arc
					(start -3.400044 1.249934)
					(mid 0 4.649978)
					(end 3.400044 1.249934)
				)
			)
			(stroke
				(width 0)
				(type default)
			)
			(fill yes)
			(layer "F.SilkS")
		)
		(fp_circle
			(center 0 1.249934)
			(end 3.400044 1.249934)
			(stroke
				(width 0.1)
				(type default)
			)
			(fill no)
			(layer "F.Fab")
		)
		(pad "1" thru_hole rect
			(at 0 0)
			(size 1.524 1.524)
			(drill 1.016)
			(layers "*.Cu" "*.Mask")
			(remove_unused_layers no)
			(net "SW_P12V_PVCCINFAON_CPU1_FLT")
			(clearance 0)
			(padstack
				(mode front_inner_back)
				(layer "Inner"
					(shape circle)
					(size 1.524 1.524)
					(clearance 0)
				)
				(layer "B.Cu"
					(shape rect)
					(size 1.524 1.524)
					(clearance 0)
				)
			)
		)
		(pad "2" thru_hole circle
			(at 0 2.500122)
			(size 1.524 1.524)
			(drill 1.016)
			(layers "*.Cu" "*.Mask")
			(remove_unused_layers no)
			(net "GND")
			(clearance 0)
		)
	)
	(footprint ""
		(layer "F.Cu")
		(at 445.19088 -97.269808 180)
		(property "Reference" "R3600"
			(at 0 0 180)
			(layer "F.SilkS")
			(hide yes)
			(effects
				(font
					(size 1.27 1.27)
				)
			)
		)
		(property "Value" ""
			(at 0 0 180)
			(layer "F.Fab")
			(effects
				(font
					(size 1.27 1.27)
				)
			)
		)
		(duplicate_pad_numbers_are_jumpers no)
		(fp_line
			(start 0.7874 0.4064)
			(end -0.7874 0.4064)
			(stroke
				(width 0.1524)
				(type default)
			)
			(layer "F.SilkS")
		)
		(fp_line
			(start 0.7874 -0.4064)
			(end 0.7874 0.4064)
			(stroke
				(width 0.1524)
				(type default)
			)
			(layer "F.SilkS")
		)
		(fp_line
			(start -0.7874 0.4064)
			(end -0.7874 -0.4064)
			(stroke
				(width 0.1524)
				(type default)
			)
			(layer "F.SilkS")
		)
		(fp_line
			(start -0.7874 -0.4064)
			(end 0.7874 -0.4064)
			(stroke
				(width 0.1524)
				(type default)
			)
			(layer "F.SilkS")
		)
		(fp_line
			(start 0.67945 0.3048)
			(end 0.120396 0.3048)
			(stroke
				(width 0.1)
				(type default)
			)
			(layer "F.Fab")
		)
		(fp_line
			(start 0.67945 -0.3048)
			(end 0.67945 0.3048)
			(stroke
				(width 0.1)
				(type default)
			)
			(layer "F.Fab")
		)
		(fp_line
			(start 0.12065 -0.2794)
			(end 0.12065 -0.3048)
			(stroke
				(width 0.1)
				(type default)
			)
			(layer "F.Fab")
		)
		(fp_line
			(start 0.12065 -0.3048)
			(end 0.67945 -0.3048)
			(stroke
				(width 0.1)
				(type default)
			)
			(layer "F.Fab")
		)
		(fp_line
			(start 0.120396 0.3048)
			(end 0.120396 0.2794)
			(stroke
				(width 0.1)
				(type default)
			)
			(layer "F.Fab")
		)
		(fp_line
			(start 0.120396 0.2794)
			(end -0.12065 0.2794)
			(stroke
				(width 0.1)
				(type default)
			)
			(layer "F.Fab")
		)
		(fp_line
			(start -0.12065 0.3048)
			(end -0.67945 0.3048)
			(stroke
				(width 0.1)
				(type default)
			)
			(layer "F.Fab")
		)
		(fp_line
			(start -0.12065 0.2794)
			(end -0.12065 0.3048)
			(stroke
				(width 0.1)
				(type default)
			)
			(layer "F.Fab")
		)
		(fp_line
			(start -0.12065 -0.2794)
			(end 0.12065 -0.2794)
			(stroke
				(width 0.1)
				(type default)
			)
			(layer "F.Fab")
		)
		(fp_line
			(start -0.12065 -0.305054)
			(end -0.12065 -0.2794)
			(stroke
				(width 0.1)
				(type default)
			)
			(layer "F.Fab")
		)
		(fp_line
			(start -0.67945 0.3048)
			(end -0.67945 -0.305054)
			(stroke
				(width 0.1)
				(type default)
			)
			(layer "F.Fab")
		)
		(fp_line
			(start -0.67945 -0.305054)
			(end -0.12065 -0.305054)
			(stroke
				(width 0.1)
				(type default)
			)
			(layer "F.Fab")
		)
		(pad "1" smd circle
			(at -0.40005 0 180)
			(size 0 0)
			(layers "F.Cu" "F.Mask" "F.Paste")
			(net "SMB_INA230_1_3V3AUX_SCL_R")
		)
		(pad "2" smd circle
			(at 0.40005 0 180)
			(size 0 0)
			(layers "F.Cu" "F.Mask" "F.Paste")
			(net "SMB_INA230_1_3V3AUX_SCL_R1")
		)
	)
	(footprint ""
		(layer "F.Cu")
		(at 204.333348 -68.5292)
		(property "Reference" "R4711"
			(at 0 0 0)
			(layer "F.SilkS")
			(hide yes)
			(effects
				(font
					(size 1.27 1.27)
				)
			)
		)
		(property "Value" ""
			(at 0 0 0)
			(layer "F.Fab")
			(effects
				(font
					(size 1.27 1.27)
				)
			)
		)
		(duplicate_pad_numbers_are_jumpers no)
		(fp_line
			(start -0.7874 -0.4064)
			(end 0.7874 -0.4064)
			(stroke
				(width 0.1524)
				(type default)
			)
			(layer "F.SilkS")
		)
		(fp_line
			(start -0.7874 0.4064)
			(end -0.7874 -0.4064)
			(stroke
				(width 0.1524)
				(type default)
			)
			(layer "F.SilkS")
		)
		(fp_line
			(start 0.7874 -0.4064)
			(end 0.7874 0.4064)
			(stroke
				(width 0.1524)
				(type default)
			)
			(layer "F.SilkS")
		)
		(fp_line
			(start 0.7874 0.4064)
			(end -0.7874 0.4064)
			(stroke
				(width 0.1524)
				(type default)
			)
			(layer "F.SilkS")
		)
		(fp_line
			(start -0.67945 -0.305054)
			(end -0.12065 -0.305054)
			(stroke
				(width 0.1)
				(type default)
			)
			(layer "F.Fab")
		)
		(fp_line
			(start -0.67945 0.3048)
			(end -0.67945 -0.305054)
			(stroke
				(width 0.1)
				(type default)
			)
			(layer "F.Fab")
		)
		(fp_line
			(start -0.12065 -0.305054)
			(end -0.12065 -0.2794)
			(stroke
				(width 0.1)
				(type default)
			)
			(layer "F.Fab")
		)
		(fp_line
			(start -0.12065 -0.2794)
			(end 0.12065 -0.2794)
			(stroke
				(width 0.1)
				(type default)
			)
			(layer "F.Fab")
		)
		(fp_line
			(start -0.12065 0.2794)
			(end -0.12065 0.3048)
			(stroke
				(width 0.1)
				(type default)
			)
			(layer "F.Fab")
		)
		(fp_line
			(start -0.12065 0.3048)
			(end -0.67945 0.3048)
			(stroke
				(width 0.1)
				(type default)
			)
			(layer "F.Fab")
		)
		(fp_line
			(start 0.120396 0.2794)
			(end -0.12065 0.2794)
			(stroke
				(width 0.1)
				(type default)
			)
			(layer "F.Fab")
		)
		(fp_line
			(start 0.120396 0.3048)
			(end 0.120396 0.2794)
			(stroke
				(width 0.1)
				(type default)
			)
			(layer "F.Fab")
		)
		(fp_line
			(start 0.12065 -0.3048)
			(end 0.67945 -0.3048)
			(stroke
				(width 0.1)
				(type default)
			)
			(layer "F.Fab")
		)
		(fp_line
			(start 0.12065 -0.2794)
			(end 0.12065 -0.3048)
			(stroke
				(width 0.1)
				(type default)
			)
			(layer "F.Fab")
		)
		(fp_line
			(start 0.67945 -0.3048)
			(end 0.67945 0.3048)
			(stroke
				(width 0.1)
				(type default)
			)
			(layer "F.Fab")
		)
		(fp_line
			(start 0.67945 0.3048)
			(end 0.120396 0.3048)
			(stroke
				(width 0.1)
				(type default)
			)
			(layer "F.Fab")
		)
		(pad "1" smd circle
			(at -0.40005 0)
			(size 0 0)
			(layers "F.Cu" "F.Mask" "F.Paste")
			(net "LED_P12V_SCM_FAULT")
		)
		(pad "2" smd circle
			(at 0.40005 0)
			(size 0 0)
			(layers "F.Cu" "F.Mask" "F.Paste")
			(net "P3V3_AUX")
		)
	)
	(footprint ""
		(layer "F.Cu")
		(at 274.7137 -95.029274 180)
		(property "Reference" "R718"
			(at 0 0 180)
			(layer "F.SilkS")
			(hide yes)
			(effects
				(font
					(size 1.27 1.27)
				)
			)
		)
		(property "Value" ""
			(at 0 0 180)
			(layer "F.Fab")
			(effects
				(font
					(size 1.27 1.27)
				)
			)
		)
		(duplicate_pad_numbers_are_jumpers no)
		(fp_line
			(start 0.7874 0.4064)
			(end -0.7874 0.4064)
			(stroke
				(width 0.1524)
				(type default)
			)
			(layer "F.SilkS")
		)
		(fp_line
			(start 0.7874 -0.4064)
			(end 0.7874 0.4064)
			(stroke
				(width 0.1524)
				(type default)
			)
			(layer "F.SilkS")
		)
		(fp_line
			(start -0.7874 0.4064)
			(end -0.7874 -0.4064)
			(stroke
				(width 0.1524)
				(type default)
			)
			(layer "F.SilkS")
		)
		(fp_line
			(start -0.7874 -0.4064)
			(end 0.7874 -0.4064)
			(stroke
				(width 0.1524)
				(type default)
			)
			(layer "F.SilkS")
		)
		(fp_line
			(start 0.67945 0.3048)
			(end 0.120396 0.3048)
			(stroke
				(width 0.1)
				(type default)
			)
			(layer "F.Fab")
		)
		(fp_line
			(start 0.67945 -0.3048)
			(end 0.67945 0.3048)
			(stroke
				(width 0.1)
				(type default)
			)
			(layer "F.Fab")
		)
		(fp_line
			(start 0.12065 -0.2794)
			(end 0.12065 -0.3048)
			(stroke
				(width 0.1)
				(type default)
			)
			(layer "F.Fab")
		)
		(fp_line
			(start 0.12065 -0.3048)
			(end 0.67945 -0.3048)
			(stroke
				(width 0.1)
				(type default)
			)
			(layer "F.Fab")
		)
		(fp_line
			(start 0.120396 0.3048)
			(end 0.120396 0.2794)
			(stroke
				(width 0.1)
				(type default)
			)
			(layer "F.Fab")
		)
		(fp_line
			(start 0.120396 0.2794)
			(end -0.12065 0.2794)
			(stroke
				(width 0.1)
				(type default)
			)
			(layer "F.Fab")
		)
		(fp_line
			(start -0.12065 0.3048)
			(end -0.67945 0.3048)
			(stroke
				(width 0.1)
				(type default)
			)
			(layer "F.Fab")
		)
		(fp_line
			(start -0.12065 0.2794)
			(end -0.12065 0.3048)
			(stroke
				(width 0.1)
				(type default)
			)
			(layer "F.Fab")
		)
		(fp_line
			(start -0.12065 -0.2794)
			(end 0.12065 -0.2794)
			(stroke
				(width 0.1)
				(type default)
			)
			(layer "F.Fab")
		)
		(fp_line
			(start -0.12065 -0.305054)
			(end -0.12065 -0.2794)
			(stroke
				(width 0.1)
				(type default)
			)
			(layer "F.Fab")
		)
		(fp_line
			(start -0.67945 0.3048)
			(end -0.67945 -0.305054)
			(stroke
				(width 0.1)
				(type default)
			)
			(layer "F.Fab")
		)
		(fp_line
			(start -0.67945 -0.305054)
			(end -0.12065 -0.305054)
			(stroke
				(width 0.1)
				(type default)
			)
			(layer "F.Fab")
		)
		(pad "1" smd circle
			(at -0.40005 0 180)
			(size 0 0)
			(layers "F.Cu" "F.Mask" "F.Paste")
			(net "MB_FRU_ADDR1")
		)
		(pad "2" smd circle
			(at 0.40005 0 180)
			(size 0 0)
			(layers "F.Cu" "F.Mask" "F.Paste")
			(net "GND")
		)
	)
	(footprint ""
		(layer "F.Cu")
		(at 335.501488 -402.371052 -90)
		(property "Reference" "C1559"
			(at 0 0 270)
			(layer "F.SilkS")
			(hide yes)
			(effects
				(font
					(size 1.27 1.27)
				)
			)
		)
		(property "Value" ""
			(at 0 0 270)
			(layer "F.Fab")
			(effects
				(font
					(size 1.27 1.27)
				)
			)
		)
		(duplicate_pad_numbers_are_jumpers no)
		(fp_line
			(start -0.299974 0.150114)
			(end -0.299974 -0.150114)
			(stroke
				(width 0.1)
				(type default)
			)
			(layer "F.Fab")
		)
		(fp_line
			(start 0.299974 0.150114)
			(end -0.299974 0.150114)
			(stroke
				(width 0.1)
				(type default)
			)
			(layer "F.Fab")
		)
		(fp_line
			(start -0.299974 -0.150114)
			(end 0.299974 -0.150114)
			(stroke
				(width 0.1)
				(type default)
			)
			(layer "F.Fab")
		)
		(fp_line
			(start 0.299974 -0.150114)
			(end 0.299974 0.150114)
			(stroke
				(width 0.1)
				(type default)
			)
			(layer "F.Fab")
		)
		(pad "1" smd rect
			(at -0.2667 0 270)
			(size 0.3048 0.381)
			(layers "F.Cu" "F.Mask" "F.Paste")
			(net "P5E_CPU0_PE4_TX_C_DP<10>")
		)
		(pad "2" smd rect
			(at 0.2667 0 270)
			(size 0.3048 0.381)
			(layers "F.Cu" "F.Mask" "F.Paste")
			(net "P5E_CPU0_PE4_TX_DP<10>")
		)
	)
	(footprint ""
		(layer "F.Cu")
		(at 193.089022 -25.965912 90)
		(property "Reference" "R4013"
			(at 0 0 90)
			(layer "F.SilkS")
			(hide yes)
			(effects
				(font
					(size 1.27 1.27)
				)
			)
		)
		(property "Value" ""
			(at 0 0 90)
			(layer "F.Fab")
			(effects
				(font
					(size 1.27 1.27)
				)
			)
		)
		(duplicate_pad_numbers_are_jumpers no)
		(fp_line
			(start 0.7874 -0.4064)
			(end 0.7874 0.4064)
			(stroke
				(width 0.1524)
				(type default)
			)
			(layer "F.SilkS")
		)
		(fp_line
			(start -0.7874 -0.4064)
			(end 0.7874 -0.4064)
			(stroke
				(width 0.1524)
				(type default)
			)
			(layer "F.SilkS")
		)
		(fp_line
			(start 0.7874 0.4064)
			(end -0.7874 0.4064)
			(stroke
				(width 0.1524)
				(type default)
			)
			(layer "F.SilkS")
		)
		(fp_line
			(start -0.7874 0.4064)
			(end -0.7874 -0.4064)
			(stroke
				(width 0.1524)
				(type default)
			)
			(layer "F.SilkS")
		)
		(fp_line
			(start -0.12065 -0.305054)
			(end -0.12065 -0.2794)
			(stroke
				(width 0.1)
				(type default)
			)
			(layer "F.Fab")
		)
		(fp_line
			(start -0.67945 -0.305054)
			(end -0.12065 -0.305054)
			(stroke
				(width 0.1)
				(type default)
			)
			(layer "F.Fab")
		)
		(fp_line
			(start 0.67945 -0.3048)
			(end 0.67945 0.3048)
			(stroke
				(width 0.1)
				(type default)
			)
			(layer "F.Fab")
		)
		(fp_line
			(start 0.12065 -0.3048)
			(end 0.67945 -0.3048)
			(stroke
				(width 0.1)
				(type default)
			)
			(layer "F.Fab")
		)
		(fp_line
			(start 0.12065 -0.2794)
			(end 0.12065 -0.3048)
			(stroke
				(width 0.1)
				(type default)
			)
			(layer "F.Fab")
		)
		(fp_line
			(start -0.12065 -0.2794)
			(end 0.12065 -0.2794)
			(stroke
				(width 0.1)
				(type default)
			)
			(layer "F.Fab")
		)
		(fp_line
			(start 0.120396 0.2794)
			(end -0.12065 0.2794)
			(stroke
				(width 0.1)
				(type default)
			)
			(layer "F.Fab")
		)
		(fp_line
			(start -0.12065 0.2794)
			(end -0.12065 0.3048)
			(stroke
				(width 0.1)
				(type default)
			)
			(layer "F.Fab")
		)
		(fp_line
			(start 0.67945 0.3048)
			(end 0.120396 0.3048)
			(stroke
				(width 0.1)
				(type default)
			)
			(layer "F.Fab")
		)
		(fp_line
			(start 0.120396 0.3048)
			(end 0.120396 0.2794)
			(stroke
				(width 0.1)
				(type default)
			)
			(layer "F.Fab")
		)
		(fp_line
			(start -0.12065 0.3048)
			(end -0.67945 0.3048)
			(stroke
				(width 0.1)
				(type default)
			)
			(layer "F.Fab")
		)
		(fp_line
			(start -0.67945 0.3048)
			(end -0.67945 -0.305054)
			(stroke
				(width 0.1)
				(type default)
			)
			(layer "F.Fab")
		)
		(pad "1" smd circle
			(at -0.40005 0 90)
			(size 0 0)
			(layers "F.Cu" "F.Mask" "F.Paste")
			(net "P3V3_AUX")
		)
		(pad "2" smd circle
			(at 0.40005 0 90)
			(size 0 0)
			(layers "F.Cu" "F.Mask" "F.Paste")
			(net "P12V_SCM_FAULT_R_N")
		)
	)
	(footprint ""
		(layer "F.Cu")
		(at 360.383582 -386.41909)
		(property "Reference" "R4158"
			(at 0 0 0)
			(layer "F.SilkS")
			(hide yes)
			(effects
				(font
					(size 1.27 1.27)
				)
			)
		)
		(property "Value" ""
			(at 0 0 0)
			(layer "F.Fab")
			(effects
				(font
					(size 1.27 1.27)
				)
			)
		)
		(duplicate_pad_numbers_are_jumpers no)
		(fp_line
			(start -0.7874 -0.4064)
			(end 0.7874 -0.4064)
			(stroke
				(width 0.1524)
				(type default)
			)
			(layer "F.SilkS")
		)
		(fp_line
			(start -0.7874 0.4064)
			(end -0.7874 -0.4064)
			(stroke
				(width 0.1524)
				(type default)
			)
			(layer "F.SilkS")
		)
		(fp_line
			(start 0.7874 -0.4064)
			(end 0.7874 0.4064)
			(stroke
				(width 0.1524)
				(type default)
			)
			(layer "F.SilkS")
		)
		(fp_line
			(start 0.7874 0.4064)
			(end -0.7874 0.4064)
			(stroke
				(width 0.1524)
				(type default)
			)
			(layer "F.SilkS")
		)
		(fp_line
			(start -0.67945 -0.305054)
			(end -0.12065 -0.305054)
			(stroke
				(width 0.1)
				(type default)
			)
			(layer "F.Fab")
		)
		(fp_line
			(start -0.67945 0.3048)
			(end -0.67945 -0.305054)
			(stroke
				(width 0.1)
				(type default)
			)
			(layer "F.Fab")
		)
		(fp_line
			(start -0.12065 -0.305054)
			(end -0.12065 -0.2794)
			(stroke
				(width 0.1)
				(type default)
			)
			(layer "F.Fab")
		)
		(fp_line
			(start -0.12065 -0.2794)
			(end 0.12065 -0.2794)
			(stroke
				(width 0.1)
				(type default)
			)
			(layer "F.Fab")
		)
		(fp_line
			(start -0.12065 0.2794)
			(end -0.12065 0.3048)
			(stroke
				(width 0.1)
				(type default)
			)
			(layer "F.Fab")
		)
		(fp_line
			(start -0.12065 0.3048)
			(end -0.67945 0.3048)
			(stroke
				(width 0.1)
				(type default)
			)
			(layer "F.Fab")
		)
		(fp_line
			(start 0.120396 0.2794)
			(end -0.12065 0.2794)
			(stroke
				(width 0.1)
				(type default)
			)
			(layer "F.Fab")
		)
		(fp_line
			(start 0.120396 0.3048)
			(end 0.120396 0.2794)
			(stroke
				(width 0.1)
				(type default)
			)
			(layer "F.Fab")
		)
		(fp_line
			(start 0.12065 -0.3048)
			(end 0.67945 -0.3048)
			(stroke
				(width 0.1)
				(type default)
			)
			(layer "F.Fab")
		)
		(fp_line
			(start 0.12065 -0.2794)
			(end 0.12065 -0.3048)
			(stroke
				(width 0.1)
				(type default)
			)
			(layer "F.Fab")
		)
		(fp_line
			(start 0.67945 -0.3048)
			(end 0.67945 0.3048)
			(stroke
				(width 0.1)
				(type default)
			)
			(layer "F.Fab")
		)
		(fp_line
			(start 0.67945 0.3048)
			(end 0.120396 0.3048)
			(stroke
				(width 0.1)
				(type default)
			)
			(layer "F.Fab")
		)
		(pad "1" smd circle
			(at -0.40005 0)
			(size 0 0)
			(layers "F.Cu" "F.Mask" "F.Paste")
			(net "P3V3_AUX")
		)
		(pad "2" smd circle
			(at 0.40005 0)
			(size 0 0)
			(layers "F.Cu" "F.Mask" "F.Paste")
			(net "GPU_3V3IO_RSVD1")
		)
	)
)
